(kicad_pcb
	(version 20260206)
	(generator "pcbnew")
	(generator_version "10.0")
	(general
		(thickness 1.6)
		(legacy_teardrops no)
	)
	(paper "A4")
	(title_block
		(title "04192023_DAF0TMB3IC0_F0TG_MB_C_brd_V02_OCP.brd")
		(comment 1 "Grand Teton / footprints 7130-7137 of 8354")
	)
	(layers
		(0 "F.Cu" signal "TOP")
		(4 "In1.Cu" signal "GND")
		(6 "In2.Cu" signal "IN1")
		(8 "In3.Cu" signal "GND1")
		(10 "In4.Cu" signal "IN2")
		(12 "In5.Cu" signal "GND2")
		(14 "In6.Cu" signal "IN3")
		(16 "In7.Cu" signal "GND3")
		(18 "In8.Cu" signal "VCC")
		(20 "In9.Cu" signal "VCC1")
		(22 "In10.Cu" signal "GND4")
		(24 "In11.Cu" signal "IN4")
		(26 "In12.Cu" signal "GND5")
		(28 "In13.Cu" signal "IN5")
		(30 "In14.Cu" signal "GND6")
		(32 "In15.Cu" signal "IN6")
		(34 "In16.Cu" signal "GND7")
		(2 "B.Cu" signal "BOTTOM")
		(9 "F.Adhes" user "F.Adhesive")
		(11 "B.Adhes" user "B.Adhesive")
		(13 "F.Paste" user "Package Geometry/Pastemask Top")
		(15 "B.Paste" user "Package Geometry/Pastemask Bottom")
		(5 "F.SilkS" user "Ref Des/Silkscreen Top")
		(7 "B.SilkS" user "Ref Des/Silkscreen Bottom")
		(1 "F.Mask" user "Board Geometry/Soldermask Top")
		(3 "B.Mask" user "Board Geometry/Soldermask Bottom")
		(17 "Dwgs.User" user "User.Drawings")
		(19 "Cmts.User" user "User.Comments")
		(21 "Eco1.User" user "User.Eco1")
		(23 "Eco2.User" user "User.Eco2")
		(25 "Edge.Cuts" user "Board Geometry/Outline")
		(27 "Margin" user)
		(31 "F.CrtYd" user "Package Geometry/Place Bound Top")
		(29 "B.CrtYd" user "Package Geometry/Place Bound Bottom")
		(35 "F.Fab" user "Ref Des/Assembly Top")
		(33 "B.Fab" user "Ref Des/Assembly Bottom")
	)
	(footprint ""
		(layer "B.Cu")
		(at 202.903582 -194.885564 180)
		(property "Reference" "R778"
			(at 0 0 0)
			(layer "B.SilkS")
			(hide yes)
			(effects
				(font
					(size 1.27 1.27)
				)
				(justify mirror)
			)
		)
		(property "Value" ""
			(at 0 0 0)
			(layer "B.Fab")
			(effects
				(font
					(size 1.27 1.27)
				)
				(justify mirror)
			)
		)
		(duplicate_pad_numbers_are_jumpers no)
		(fp_line
			(start 0.7874 0.4064)
			(end 0.7874 -0.4064)
			(stroke
				(width 0.1524)
				(type default)
			)
			(layer "B.SilkS")
		)
		(fp_line
			(start 0.7874 -0.4064)
			(end -0.7874 -0.4064)
			(stroke
				(width 0.1524)
				(type default)
			)
			(layer "B.SilkS")
		)
		(fp_line
			(start -0.7874 0.4064)
			(end 0.7874 0.4064)
			(stroke
				(width 0.1524)
				(type default)
			)
			(layer "B.SilkS")
		)
		(fp_line
			(start -0.7874 -0.4064)
			(end -0.7874 0.4064)
			(stroke
				(width 0.1524)
				(type default)
			)
			(layer "B.SilkS")
		)
		(fp_line
			(start 0.67945 0.3048)
			(end 0.67945 -0.305054)
			(stroke
				(width 0.1)
				(type default)
			)
			(layer "B.Fab")
		)
		(fp_line
			(start 0.67945 -0.305054)
			(end 0.12065 -0.305054)
			(stroke
				(width 0.1)
				(type default)
			)
			(layer "B.Fab")
		)
		(fp_line
			(start 0.12065 0.3048)
			(end 0.67945 0.3048)
			(stroke
				(width 0.1)
				(type default)
			)
			(layer "B.Fab")
		)
		(fp_line
			(start 0.12065 0.2794)
			(end 0.12065 0.3048)
			(stroke
				(width 0.1)
				(type default)
			)
			(layer "B.Fab")
		)
		(fp_line
			(start 0.12065 -0.2794)
			(end -0.12065 -0.2794)
			(stroke
				(width 0.1)
				(type default)
			)
			(layer "B.Fab")
		)
		(fp_line
			(start 0.12065 -0.305054)
			(end 0.12065 -0.2794)
			(stroke
				(width 0.1)
				(type default)
			)
			(layer "B.Fab")
		)
		(fp_line
			(start -0.120396 0.3048)
			(end -0.120396 0.2794)
			(stroke
				(width 0.1)
				(type default)
			)
			(layer "B.Fab")
		)
		(fp_line
			(start -0.120396 0.2794)
			(end 0.12065 0.2794)
			(stroke
				(width 0.1)
				(type default)
			)
			(layer "B.Fab")
		)
		(fp_line
			(start -0.12065 -0.2794)
			(end -0.12065 -0.3048)
			(stroke
				(width 0.1)
				(type default)
			)
			(layer "B.Fab")
		)
		(fp_line
			(start -0.12065 -0.3048)
			(end -0.67945 -0.3048)
			(stroke
				(width 0.1)
				(type default)
			)
			(layer "B.Fab")
		)
		(fp_line
			(start -0.67945 0.3048)
			(end -0.120396 0.3048)
			(stroke
				(width 0.1)
				(type default)
			)
			(layer "B.Fab")
		)
		(fp_line
			(start -0.67945 -0.3048)
			(end -0.67945 0.3048)
			(stroke
				(width 0.1)
				(type default)
			)
			(layer "B.Fab")
		)
		(pad "1" smd circle
			(at 0.40005 0)
			(size 0 0)
			(layers "B.Cu" "B.Mask" "B.Paste")
			(net "PD_CHL_CPU1_DIMM_SAA")
		)
		(pad "2" smd circle
			(at -0.40005 0)
			(size 0 0)
			(layers "B.Cu" "B.Mask" "B.Paste")
			(net "GND")
		)
	)
	(footprint ""
		(layer "B.Cu")
		(at 216.13368 -329.179174 180)
		(property "Reference" "R1239"
			(at 0 0 0)
			(layer "B.SilkS")
			(hide yes)
			(effects
				(font
					(size 1.27 1.27)
				)
				(justify mirror)
			)
		)
		(property "Value" ""
			(at 0 0 0)
			(layer "B.Fab")
			(effects
				(font
					(size 1.27 1.27)
				)
				(justify mirror)
			)
		)
		(duplicate_pad_numbers_are_jumpers no)
		(fp_line
			(start 0.7874 0.4064)
			(end 0.7874 -0.4064)
			(stroke
				(width 0.1524)
				(type default)
			)
			(layer "B.SilkS")
		)
		(fp_line
			(start 0.7874 -0.4064)
			(end -0.7874 -0.4064)
			(stroke
				(width 0.1524)
				(type default)
			)
			(layer "B.SilkS")
		)
		(fp_line
			(start -0.7874 0.4064)
			(end 0.7874 0.4064)
			(stroke
				(width 0.1524)
				(type default)
			)
			(layer "B.SilkS")
		)
		(fp_line
			(start -0.7874 -0.4064)
			(end -0.7874 0.4064)
			(stroke
				(width 0.1524)
				(type default)
			)
			(layer "B.SilkS")
		)
		(fp_line
			(start 0.67945 0.3048)
			(end 0.67945 -0.305054)
			(stroke
				(width 0.1)
				(type default)
			)
			(layer "B.Fab")
		)
		(fp_line
			(start 0.67945 -0.305054)
			(end 0.12065 -0.305054)
			(stroke
				(width 0.1)
				(type default)
			)
			(layer "B.Fab")
		)
		(fp_line
			(start 0.12065 0.3048)
			(end 0.67945 0.3048)
			(stroke
				(width 0.1)
				(type default)
			)
			(layer "B.Fab")
		)
		(fp_line
			(start 0.12065 0.2794)
			(end 0.12065 0.3048)
			(stroke
				(width 0.1)
				(type default)
			)
			(layer "B.Fab")
		)
		(fp_line
			(start 0.12065 -0.2794)
			(end -0.12065 -0.2794)
			(stroke
				(width 0.1)
				(type default)
			)
			(layer "B.Fab")
		)
		(fp_line
			(start 0.12065 -0.305054)
			(end 0.12065 -0.2794)
			(stroke
				(width 0.1)
				(type default)
			)
			(layer "B.Fab")
		)
		(fp_line
			(start -0.120396 0.3048)
			(end -0.120396 0.2794)
			(stroke
				(width 0.1)
				(type default)
			)
			(layer "B.Fab")
		)
		(fp_line
			(start -0.120396 0.2794)
			(end 0.12065 0.2794)
			(stroke
				(width 0.1)
				(type default)
			)
			(layer "B.Fab")
		)
		(fp_line
			(start -0.12065 -0.2794)
			(end -0.12065 -0.3048)
			(stroke
				(width 0.1)
				(type default)
			)
			(layer "B.Fab")
		)
		(fp_line
			(start -0.12065 -0.3048)
			(end -0.67945 -0.3048)
			(stroke
				(width 0.1)
				(type default)
			)
			(layer "B.Fab")
		)
		(fp_line
			(start -0.67945 0.3048)
			(end -0.120396 0.3048)
			(stroke
				(width 0.1)
				(type default)
			)
			(layer "B.Fab")
		)
		(fp_line
			(start -0.67945 -0.3048)
			(end -0.67945 0.3048)
			(stroke
				(width 0.1)
				(type default)
			)
			(layer "B.Fab")
		)
		(pad "1" smd circle
			(at 0.40005 0)
			(size 0 0)
			(layers "B.Cu" "B.Mask" "B.Paste")
			(net "P3V3_AUX")
		)
		(pad "2" smd circle
			(at -0.40005 0)
			(size 0 0)
			(layers "B.Cu" "B.Mask" "B.Paste")
			(net "ADC128_2_A1")
		)
	)
	(footprint ""
		(layer "B.Cu")
		(at 367.186464 -63.155068)
		(property "Reference" "ME13"
			(at 0 0 0)
			(layer "B.SilkS")
			(hide yes)
			(effects
				(font
					(size 1.27 1.27)
				)
				(justify mirror)
			)
		)
		(property "Value" ""
			(at 0 0 0)
			(layer "B.Fab")
			(effects
				(font
					(size 1.27 1.27)
				)
				(justify mirror)
			)
		)
		(duplicate_pad_numbers_are_jumpers no)
		(zone
			(layer "B.Cu")
			(hatch none 0.5)
			(connect_pads
				(clearance 0)
			)
			(min_thickness 0.25)
			(keepout
				(tracks allowed)
				(vias allowed)
				(pads allowed)
				(copperpour allowed)
				(footprints not_allowed)
			)
			(placement
				(enabled no)
				(sheetname "")
			)
			(fill
				(thermal_gap 0.5)
				(thermal_bridge_width 0.5)
				(island_removal_mode 0)
			)
			(polygon
				(pts
					(arc
						(start 377.186444 -63.155068)
						(mid 357.186484 -63.155068)
						(end 377.186444 -63.155068)
					)
				)
			)
		)
	)
	(footprint ""
		(layer "B.Cu")
		(at 304.055018 -409.560014 90)
		(property "Reference" "PJ09_P0_P"
			(at 0 0 90)
			(layer "B.SilkS")
			(hide yes)
			(effects
				(font
					(size 1.27 1.27)
				)
				(justify mirror)
			)
		)
		(property "Value" ""
			(at 0 0 90)
			(layer "B.Fab")
			(effects
				(font
					(size 1.27 1.27)
				)
				(justify mirror)
			)
		)
		(duplicate_pad_numbers_are_jumpers no)
		(zone
			(layer "In11.Cu")
			(hatch none 0.5)
			(connect_pads
				(clearance 0)
			)
			(min_thickness 0.25)
			(keepout
				(tracks allowed)
				(vias not_allowed)
				(pads allowed)
				(copperpour not_allowed)
				(footprints allowed)
			)
			(placement
				(enabled no)
				(sheetname "")
			)
			(fill
				(thermal_gap 0.5)
				(thermal_bridge_width 0.5)
				(island_removal_mode 0)
			)
			(polygon
				(pts
					(xy 304.245518 -409.775914) (xy 304.245518 -409.344114) (xy 303.864518 -409.344114) (xy 303.864518 -409.775914)
				)
			)
		)
	)
	(footprint ""
		(layer "B.Cu")
		(at 237.90148 -327.698608)
		(property "Reference" "R1233"
			(at 0 0 0)
			(layer "B.SilkS")
			(hide yes)
			(effects
				(font
					(size 1.27 1.27)
				)
				(justify mirror)
			)
		)
		(property "Value" ""
			(at 0 0 0)
			(layer "B.Fab")
			(effects
				(font
					(size 1.27 1.27)
				)
				(justify mirror)
			)
		)
		(duplicate_pad_numbers_are_jumpers no)
		(fp_line
			(start -0.7874 -0.4064)
			(end -0.7874 0.4064)
			(stroke
				(width 0.1524)
				(type default)
			)
			(layer "B.SilkS")
		)
		(fp_line
			(start -0.7874 0.4064)
			(end 0.7874 0.4064)
			(stroke
				(width 0.1524)
				(type default)
			)
			(layer "B.SilkS")
		)
		(fp_line
			(start 0.7874 -0.4064)
			(end -0.7874 -0.4064)
			(stroke
				(width 0.1524)
				(type default)
			)
			(layer "B.SilkS")
		)
		(fp_line
			(start 0.7874 0.4064)
			(end 0.7874 -0.4064)
			(stroke
				(width 0.1524)
				(type default)
			)
			(layer "B.SilkS")
		)
		(fp_line
			(start -0.67945 -0.3048)
			(end -0.67945 0.3048)
			(stroke
				(width 0.1)
				(type default)
			)
			(layer "B.Fab")
		)
		(fp_line
			(start -0.67945 0.3048)
			(end -0.120396 0.3048)
			(stroke
				(width 0.1)
				(type default)
			)
			(layer "B.Fab")
		)
		(fp_line
			(start -0.12065 -0.3048)
			(end -0.67945 -0.3048)
			(stroke
				(width 0.1)
				(type default)
			)
			(layer "B.Fab")
		)
		(fp_line
			(start -0.12065 -0.2794)
			(end -0.12065 -0.3048)
			(stroke
				(width 0.1)
				(type default)
			)
			(layer "B.Fab")
		)
		(fp_line
			(start -0.120396 0.2794)
			(end 0.12065 0.2794)
			(stroke
				(width 0.1)
				(type default)
			)
			(layer "B.Fab")
		)
		(fp_line
			(start -0.120396 0.3048)
			(end -0.120396 0.2794)
			(stroke
				(width 0.1)
				(type default)
			)
			(layer "B.Fab")
		)
		(fp_line
			(start 0.12065 -0.305054)
			(end 0.12065 -0.2794)
			(stroke
				(width 0.1)
				(type default)
			)
			(layer "B.Fab")
		)
		(fp_line
			(start 0.12065 -0.2794)
			(end -0.12065 -0.2794)
			(stroke
				(width 0.1)
				(type default)
			)
			(layer "B.Fab")
		)
		(fp_line
			(start 0.12065 0.2794)
			(end 0.12065 0.3048)
			(stroke
				(width 0.1)
				(type default)
			)
			(layer "B.Fab")
		)
		(fp_line
			(start 0.12065 0.3048)
			(end 0.67945 0.3048)
			(stroke
				(width 0.1)
				(type default)
			)
			(layer "B.Fab")
		)
		(fp_line
			(start 0.67945 -0.305054)
			(end 0.12065 -0.305054)
			(stroke
				(width 0.1)
				(type default)
			)
			(layer "B.Fab")
		)
		(fp_line
			(start 0.67945 0.3048)
			(end 0.67945 -0.305054)
			(stroke
				(width 0.1)
				(type default)
			)
			(layer "B.Fab")
		)
		(pad "1" smd circle
			(at 0.40005 0 180)
			(size 0 0)
			(layers "B.Cu" "B.Mask" "B.Paste")
			(net "PVDD18_S5_P0")
		)
		(pad "2" smd circle
			(at -0.40005 0 180)
			(size 0 0)
			(layers "B.Cu" "B.Mask" "B.Paste")
			(net "PVDD18_S5_P0_ADC")
		)
	)
	(footprint ""
		(layer "B.Cu")
		(at 51.120548 -193.996564)
		(property "Reference" "C140"
			(at 0 0 0)
			(layer "B.SilkS")
			(hide yes)
			(effects
				(font
					(size 1.27 1.27)
				)
				(justify mirror)
			)
		)
		(property "Value" ""
			(at 0 0 0)
			(layer "B.Fab")
			(effects
				(font
					(size 1.27 1.27)
				)
				(justify mirror)
			)
		)
		(duplicate_pad_numbers_are_jumpers no)
		(fp_line
			(start -0.7874 -0.4064)
			(end -0.7874 0.4064)
			(stroke
				(width 0.1524)
				(type default)
			)
			(layer "B.SilkS")
		)
		(fp_line
			(start -0.7874 0.4064)
			(end 0.7874 0.4064)
			(stroke
				(width 0.1524)
				(type default)
			)
			(layer "B.SilkS")
		)
		(fp_line
			(start 0.7874 -0.4064)
			(end -0.7874 -0.4064)
			(stroke
				(width 0.1524)
				(type default)
			)
			(layer "B.SilkS")
		)
		(fp_line
			(start 0.7874 0.4064)
			(end 0.7874 -0.4064)
			(stroke
				(width 0.1524)
				(type default)
			)
			(layer "B.SilkS")
		)
		(fp_line
			(start -0.67945 -0.3048)
			(end -0.67945 0.3048)
			(stroke
				(width 0.1)
				(type default)
			)
			(layer "B.Fab")
		)
		(fp_line
			(start -0.67945 0.3048)
			(end -0.120396 0.3048)
			(stroke
				(width 0.1)
				(type default)
			)
			(layer "B.Fab")
		)
		(fp_line
			(start -0.12065 -0.3048)
			(end -0.67945 -0.3048)
			(stroke
				(width 0.1)
				(type default)
			)
			(layer "B.Fab")
		)
		(fp_line
			(start -0.12065 -0.2794)
			(end -0.12065 -0.3048)
			(stroke
				(width 0.1)
				(type default)
			)
			(layer "B.Fab")
		)
		(fp_line
			(start -0.120396 0.2794)
			(end 0.12065 0.2794)
			(stroke
				(width 0.1)
				(type default)
			)
			(layer "B.Fab")
		)
		(fp_line
			(start -0.120396 0.3048)
			(end -0.120396 0.2794)
			(stroke
				(width 0.1)
				(type default)
			)
			(layer "B.Fab")
		)
		(fp_line
			(start 0.12065 -0.305054)
			(end 0.12065 -0.2794)
			(stroke
				(width 0.1)
				(type default)
			)
			(layer "B.Fab")
		)
		(fp_line
			(start 0.12065 -0.2794)
			(end -0.12065 -0.2794)
			(stroke
				(width 0.1)
				(type default)
			)
			(layer "B.Fab")
		)
		(fp_line
			(start 0.12065 0.2794)
			(end 0.12065 0.3048)
			(stroke
				(width 0.1)
				(type default)
			)
			(layer "B.Fab")
		)
		(fp_line
			(start 0.12065 0.3048)
			(end 0.67945 0.3048)
			(stroke
				(width 0.1)
				(type default)
			)
			(layer "B.Fab")
		)
		(fp_line
			(start 0.67945 -0.305054)
			(end 0.12065 -0.305054)
			(stroke
				(width 0.1)
				(type default)
			)
			(layer "B.Fab")
		)
		(fp_line
			(start 0.67945 0.3048)
			(end 0.67945 -0.305054)
			(stroke
				(width 0.1)
				(type default)
			)
			(layer "B.Fab")
		)
		(pad "1" smd circle
			(at 0.40005 0 180)
			(size 0 0)
			(layers "B.Cu" "B.Mask" "B.Paste")
			(net "P3V3_AUX")
		)
		(pad "2" smd circle
			(at -0.40005 0 180)
			(size 0 0)
			(layers "B.Cu" "B.Mask" "B.Paste")
			(net "GND")
		)
	)
	(footprint ""
		(layer "B.Cu")
		(at 387.716522 -416.899344 90)
		(property "Reference" "C6608"
			(at 0 0 90)
			(layer "B.SilkS")
			(hide yes)
			(effects
				(font
					(size 1.27 1.27)
				)
				(justify mirror)
			)
		)
		(property "Value" ""
			(at 0 0 90)
			(layer "B.Fab")
			(effects
				(font
					(size 1.27 1.27)
				)
				(justify mirror)
			)
		)
		(duplicate_pad_numbers_are_jumpers no)
		(fp_line
			(start 0.299974 -0.150114)
			(end -0.299974 -0.150114)
			(stroke
				(width 0.1)
				(type default)
			)
			(layer "B.Fab")
		)
		(fp_line
			(start -0.299974 -0.150114)
			(end -0.299974 0.150114)
			(stroke
				(width 0.1)
				(type default)
			)
			(layer "B.Fab")
		)
		(fp_line
			(start 0.299974 0.150114)
			(end 0.299974 -0.150114)
			(stroke
				(width 0.1)
				(type default)
			)
			(layer "B.Fab")
		)
		(fp_line
			(start -0.299974 0.150114)
			(end 0.299974 0.150114)
			(stroke
				(width 0.1)
				(type default)
			)
			(layer "B.Fab")
		)
		(pad "1" smd rect
			(at 0.2667 0 270)
			(size 0.3048 0.381)
			(layers "B.Cu" "B.Mask" "B.Paste")
			(net "P5E_CPU0_P3_TX_BUF_C_DN<5>")
		)
		(pad "2" smd rect
			(at -0.2667 0 270)
			(size 0.3048 0.381)
			(layers "B.Cu" "B.Mask" "B.Paste")
			(net "P5E_CPU0_P3_TX_BUF_DN<5>")
		)
	)
	(footprint ""
		(layer "B.Cu")
		(at 337.687158 -309.214012 -90)
		(property "Reference" "R394"
			(at 0 0 90)
			(layer "B.SilkS")
			(hide yes)
			(effects
				(font
					(size 1.27 1.27)
				)
				(justify mirror)
			)
		)
		(property "Value" ""
			(at 0 0 90)
			(layer "B.Fab")
			(effects
				(font
					(size 1.27 1.27)
				)
				(justify mirror)
			)
		)
		(duplicate_pad_numbers_are_jumpers no)
		(fp_line
			(start -0.7874 0.4064)
			(end 0.7874 0.4064)
			(stroke
				(width 0.1524)
				(type default)
			)
			(layer "B.SilkS")
		)
		(fp_line
			(start 0.7874 0.4064)
			(end 0.7874 -0.4064)
			(stroke
				(width 0.1524)
				(type default)
			)
			(layer "B.SilkS")
		)
		(fp_line
			(start -0.7874 -0.4064)
			(end -0.7874 0.4064)
			(stroke
				(width 0.1524)
				(type default)
			)
			(layer "B.SilkS")
		)
		(fp_line
			(start 0.7874 -0.4064)
			(end -0.7874 -0.4064)
			(stroke
				(width 0.1524)
				(type default)
			)
			(layer "B.SilkS")
		)
		(fp_line
			(start -0.67945 0.3048)
			(end -0.120396 0.3048)
			(stroke
				(width 0.1)
				(type default)
			)
			(layer "B.Fab")
		)
		(fp_line
			(start -0.120396 0.3048)
			(end -0.120396 0.2794)
			(stroke
				(width 0.1)
				(type default)
			)
			(layer "B.Fab")
		)
		(fp_line
			(start 0.12065 0.3048)
			(end 0.67945 0.3048)
			(stroke
				(width 0.1)
				(type default)
			)
			(layer "B.Fab")
		)
		(fp_line
			(start 0.67945 0.3048)
			(end 0.67945 -0.305054)
			(stroke
				(width 0.1)
				(type default)
			)
			(layer "B.Fab")
		)
		(fp_line
			(start -0.120396 0.2794)
			(end 0.12065 0.2794)
			(stroke
				(width 0.1)
				(type default)
			)
			(layer "B.Fab")
		)
		(fp_line
			(start 0.12065 0.2794)
			(end 0.12065 0.3048)
			(stroke
				(width 0.1)
				(type default)
			)
			(layer "B.Fab")
		)
		(fp_line
			(start -0.12065 -0.2794)
			(end -0.12065 -0.3048)
			(stroke
				(width 0.1)
				(type default)
			)
			(layer "B.Fab")
		)
		(fp_line
			(start 0.12065 -0.2794)
			(end -0.12065 -0.2794)
			(stroke
				(width 0.1)
				(type default)
			)
			(layer "B.Fab")
		)
		(fp_line
			(start -0.67945 -0.3048)
			(end -0.67945 0.3048)
			(stroke
				(width 0.1)
				(type default)
			)
			(layer "B.Fab")
		)
		(fp_line
			(start -0.12065 -0.3048)
			(end -0.67945 -0.3048)
			(stroke
				(width 0.1)
				(type default)
			)
			(layer "B.Fab")
		)
		(fp_line
			(start 0.12065 -0.305054)
			(end 0.12065 -0.2794)
			(stroke
				(width 0.1)
				(type default)
			)
			(layer "B.Fab")
		)
		(fp_line
			(start 0.67945 -0.305054)
			(end 0.12065 -0.305054)
			(stroke
				(width 0.1)
				(type default)
			)
			(layer "B.Fab")
		)
		(pad "1" smd circle
			(at 0.40005 0 90)
			(size 0 0)
			(layers "B.Cu" "B.Mask" "B.Paste")
			(net "CPU0_SA1")
		)
		(pad "2" smd circle
			(at -0.40005 0 90)
			(size 0 0)
			(layers "B.Cu" "B.Mask" "B.Paste")
			(net "GND")
		)
	)
)
